(kicad_pcb
	(version 20260206)
	(generator "pcbnew")
	(generator_version "10.0")
	(general
		(thickness 1.6)
		(legacy_teardrops no)
	)
	(paper "A4")
	(title_block
		(title "peb — Lightning_PEB_BRD.brd")
		(comment 1 "Lightning (Wiwynn / Facebook NVMe JBOF) / footprints 2116-2122 of 2563")
	)
	(layers
		(0 "F.Cu" signal "TOP")
		(4 "In1.Cu" signal "L2GND")
		(6 "In2.Cu" signal "L3")
		(8 "In3.Cu" signal "L4VCC")
		(10 "In4.Cu" signal "L5VCC")
		(12 "In5.Cu" signal "L6")
		(14 "In6.Cu" signal "L7GND")
		(2 "B.Cu" signal "BOTTOM")
		(9 "F.Adhes" user "F.Adhesive")
		(11 "B.Adhes" user "B.Adhesive")
		(13 "F.Paste" user "Package Geometry/Pastemask Top")
		(15 "B.Paste" user "Package Geometry/Pastemask Bottom")
		(5 "F.SilkS" user "Ref Des/Silkscreen Top")
		(7 "B.SilkS" user "Ref Des/Silkscreen Bottom")
		(1 "F.Mask" user "Board Geometry/Soldermask Top")
		(3 "B.Mask" user "Board Geometry/Soldermask Bottom")
		(17 "Dwgs.User" user "User.Drawings")
		(19 "Cmts.User" user "User.Comments")
		(21 "Eco1.User" user "User.Eco1")
		(23 "Eco2.User" user "User.Eco2")
		(25 "Edge.Cuts" user "Board Geometry/Outline")
		(27 "Margin" user)
		(31 "F.CrtYd" user "Package Geometry/Place Bound Top")
		(29 "B.CrtYd" user "Package Geometry/Place Bound Bottom")
		(35 "F.Fab" user "Ref Des/Assembly Top")
		(33 "B.Fab" user "Ref Des/Assembly Bottom")
	)
	(footprint ""
		(layer "B.Cu")
		(at 75.184 -148.082 -90)
		(property "Reference" "R193"
			(at 0 0 90)
			(layer "B.SilkS")
			(hide yes)
			(effects
				(font
					(size 1.27 1.27)
				)
				(justify mirror)
			)
		)
		(property "Value" "8K2R2J-3-GP"
			(at -0.064008 -3.993896 270)
			(unlocked yes)
			(layer "B.Fab")
			(hide yes)
			(effects
				(font
					(size 1.016 1.016)
					(thickness 0.1524)
				)
				(justify mirror)
			)
		)
		(property "Device Type" "R402H16"
			(at -0.064008 -5.517896 270)
			(unlocked yes)
			(layer "B.Fab")
			(hide yes)
			(effects
				(font
					(size 1.016 1.016)
					(thickness 0.1524)
				)
				(justify mirror)
			)
		)
		(duplicate_pad_numbers_are_jumpers no)
		(fp_line
			(start -0.508 -0.9398)
			(end 0.508 -0.9398)
			(stroke
				(width 0.1524)
				(type default)
			)
			(layer "B.SilkS")
		)
		(fp_line
			(start 0.508 -0.9398)
			(end 0.508 0.9398)
			(stroke
				(width 0.1524)
				(type default)
			)
			(layer "B.SilkS")
		)
		(fp_rect
			(start 0.508 0.9398)
			(end -0.508 -0.9398)
			(stroke
				(width 0)
				(type default)
			)
			(fill no)
			(layer "B.CrtYd")
		)
		(fp_rect
			(start 0.508 0.9398)
			(end -0.508 -0.9398)
			(stroke
				(width 0)
				(type default)
			)
			(fill no)
			(layer "B.Fab")
		)
		(pad "1" smd custom
			(at 0 -0.4445 90)
			(size 0.1397 0.1397)
			(layers "B.Cu" "B.Mask" "B.Paste")
			(net "P3V3_STBY")
			(options
				(clearance outline)
				(anchor circle)
			)
			(primitives
				(gr_poly
					(pts
						(arc
							(start -0.1778 0.2794)
							(mid -0.249642 0.249642)
							(end -0.2794 0.1778)
						)
						(arc
							(start -0.2794 -0.1778)
							(mid -0.249642 -0.249642)
							(end -0.1778 -0.2794)
						)
						(arc
							(start 0.1778 -0.2794)
							(mid 0.249642 -0.249642)
							(end 0.2794 -0.1778)
						)
						(arc
							(start 0.2794 0.1778)
							(mid 0.249642 0.249642)
							(end 0.1778 0.2794)
						)
					)
					(width 0)
					(fill yes)
				)
			)
		)
		(pad "2" smd custom
			(at 0 0.4445 90)
			(size 0.1397 0.1397)
			(layers "B.Cu" "B.Mask" "B.Paste")
			(net "EEPROM_A1_R")
			(options
				(clearance outline)
				(anchor circle)
			)
			(primitives
				(gr_poly
					(pts
						(arc
							(start -0.1778 0.2794)
							(mid -0.249642 0.249642)
							(end -0.2794 0.1778)
						)
						(arc
							(start -0.2794 -0.1778)
							(mid -0.249642 -0.249642)
							(end -0.1778 -0.2794)
						)
						(arc
							(start 0.1778 -0.2794)
							(mid 0.249642 -0.249642)
							(end 0.2794 -0.1778)
						)
						(arc
							(start 0.2794 0.1778)
							(mid 0.249642 0.249642)
							(end 0.1778 0.2794)
						)
					)
					(width 0)
					(fill yes)
				)
			)
		)
	)
	(footprint ""
		(layer "B.Cu")
		(at 51.2318 -115.90909)
		(property "Reference" "R470"
			(at 0 0 0)
			(layer "B.SilkS")
			(hide yes)
			(effects
				(font
					(size 1.27 1.27)
				)
				(justify mirror)
			)
		)
		(property "Value" "0R2J-2-GP"
			(at -0.064008 -3.993896 0)
			(unlocked yes)
			(layer "B.Fab")
			(hide yes)
			(effects
				(font
					(size 1.016 1.016)
					(thickness 0.1524)
				)
				(justify mirror)
			)
		)
		(property "Device Type" "R402H16"
			(at -0.064008 -5.517896 0)
			(unlocked yes)
			(layer "B.Fab")
			(hide yes)
			(effects
				(font
					(size 1.016 1.016)
					(thickness 0.1524)
				)
				(justify mirror)
			)
		)
		(duplicate_pad_numbers_are_jumpers no)
		(fp_line
			(start -0.508 -0.9398)
			(end 0.508 -0.9398)
			(stroke
				(width 0.1524)
				(type default)
			)
			(layer "B.SilkS")
		)
		(fp_line
			(start 0.508 -0.9398)
			(end 0.508 0.9398)
			(stroke
				(width 0.1524)
				(type default)
			)
			(layer "B.SilkS")
		)
		(fp_rect
			(start 0.508 0.9398)
			(end -0.508 -0.9398)
			(stroke
				(width 0)
				(type default)
			)
			(fill no)
			(layer "B.CrtYd")
		)
		(fp_rect
			(start 0.508 0.9398)
			(end -0.508 -0.9398)
			(stroke
				(width 0)
				(type default)
			)
			(fill no)
			(layer "B.Fab")
		)
		(pad "1" smd custom
			(at 0 -0.4445 180)
			(size 0.1397 0.1397)
			(layers "B.Cu" "B.Mask" "B.Paste")
			(net "BMC0_SMB10_DAT")
			(options
				(clearance outline)
				(anchor circle)
			)
			(primitives
				(gr_poly
					(pts
						(arc
							(start -0.1778 0.2794)
							(mid -0.249642 0.249642)
							(end -0.2794 0.1778)
						)
						(arc
							(start -0.2794 -0.1778)
							(mid -0.249642 -0.249642)
							(end -0.1778 -0.2794)
						)
						(arc
							(start 0.1778 -0.2794)
							(mid 0.249642 -0.249642)
							(end 0.2794 -0.1778)
						)
						(arc
							(start 0.2794 0.1778)
							(mid 0.249642 0.249642)
							(end 0.1778 0.2794)
						)
					)
					(width 0)
					(fill yes)
				)
			)
		)
		(pad "2" smd custom
			(at 0 0.4445 180)
			(size 0.1397 0.1397)
			(layers "B.Cu" "B.Mask" "B.Paste")
			(net "BMC_I2C10_8536_SDA")
			(options
				(clearance outline)
				(anchor circle)
			)
			(primitives
				(gr_poly
					(pts
						(arc
							(start -0.1778 0.2794)
							(mid -0.249642 0.249642)
							(end -0.2794 0.1778)
						)
						(arc
							(start -0.2794 -0.1778)
							(mid -0.249642 -0.249642)
							(end -0.1778 -0.2794)
						)
						(arc
							(start 0.1778 -0.2794)
							(mid 0.249642 -0.249642)
							(end 0.2794 -0.1778)
						)
						(arc
							(start 0.2794 0.1778)
							(mid 0.249642 0.249642)
							(end 0.1778 0.2794)
						)
					)
					(width 0)
					(fill yes)
				)
			)
		)
	)
	(footprint ""
		(layer "B.Cu")
		(at 133.55828 -33.54578)
		(property "Reference" "R2918"
			(at 0 0 0)
			(layer "B.SilkS")
			(hide yes)
			(effects
				(font
					(size 1.27 1.27)
				)
				(justify mirror)
			)
		)
		(property "Value" "0R2J-2-GP"
			(at -0.064008 -3.993896 0)
			(unlocked yes)
			(layer "B.Fab")
			(hide yes)
			(effects
				(font
					(size 1.016 1.016)
					(thickness 0.1524)
				)
				(justify mirror)
			)
		)
		(property "Device Type" "R402H16"
			(at -0.064008 -5.517896 0)
			(unlocked yes)
			(layer "B.Fab")
			(hide yes)
			(effects
				(font
					(size 1.016 1.016)
					(thickness 0.1524)
				)
				(justify mirror)
			)
		)
		(duplicate_pad_numbers_are_jumpers no)
		(fp_line
			(start -0.508 -0.9398)
			(end 0.508 -0.9398)
			(stroke
				(width 0.1524)
				(type default)
			)
			(layer "B.SilkS")
		)
		(fp_line
			(start 0.508 -0.9398)
			(end 0.508 0.9398)
			(stroke
				(width 0.1524)
				(type default)
			)
			(layer "B.SilkS")
		)
		(fp_rect
			(start 0.508 0.9398)
			(end -0.508 -0.9398)
			(stroke
				(width 0)
				(type default)
			)
			(fill no)
			(layer "B.CrtYd")
		)
		(fp_rect
			(start 0.508 0.9398)
			(end -0.508 -0.9398)
			(stroke
				(width 0)
				(type default)
			)
			(fill no)
			(layer "B.Fab")
		)
		(pad "1" smd custom
			(at 0 -0.4445 180)
			(size 0.1397 0.1397)
			(layers "B.Cu" "B.Mask" "B.Paste")
			(net "CBL_PRSNT_N_1")
			(options
				(clearance outline)
				(anchor circle)
			)
			(primitives
				(gr_poly
					(pts
						(arc
							(start -0.1778 0.2794)
							(mid -0.249642 0.249642)
							(end -0.2794 0.1778)
						)
						(arc
							(start -0.2794 -0.1778)
							(mid -0.249642 -0.249642)
							(end -0.1778 -0.2794)
						)
						(arc
							(start 0.1778 -0.2794)
							(mid 0.249642 -0.249642)
							(end 0.2794 -0.1778)
						)
						(arc
							(start 0.2794 0.1778)
							(mid 0.249642 0.249642)
							(end 0.1778 0.2794)
						)
					)
					(width 0)
					(fill yes)
				)
			)
		)
		(pad "2" smd custom
			(at 0 0.4445 180)
			(size 0.1397 0.1397)
			(layers "B.Cu" "B.Mask" "B.Paste")
			(net "8644_CBL_PRSNT_R_1")
			(options
				(clearance outline)
				(anchor circle)
			)
			(primitives
				(gr_poly
					(pts
						(arc
							(start -0.1778 0.2794)
							(mid -0.249642 0.249642)
							(end -0.2794 0.1778)
						)
						(arc
							(start -0.2794 -0.1778)
							(mid -0.249642 -0.249642)
							(end -0.1778 -0.2794)
						)
						(arc
							(start 0.1778 -0.2794)
							(mid 0.249642 -0.249642)
							(end 0.2794 -0.1778)
						)
						(arc
							(start 0.2794 0.1778)
							(mid 0.249642 0.249642)
							(end 0.1778 0.2794)
						)
					)
					(width 0)
					(fill yes)
				)
			)
		)
	)
	(footprint ""
		(layer "B.Cu")
		(at 243.586 -59.0042 -90)
		(property "Reference" "C508"
			(at 0 0 90)
			(layer "B.SilkS")
			(hide yes)
			(effects
				(font
					(size 1.27 1.27)
				)
				(justify mirror)
			)
		)
		(property "Value" "SCD1U16V1KX-1-GP"
			(at 2.8321 -1.7399 270)
			(unlocked yes)
			(layer "B.Fab")
			(hide yes)
			(effects
				(font
					(size 1.016 1.016)
					(thickness 0.1524)
				)
				(justify mirror)
			)
		)
		(property "Device Type" "C0201H13"
			(at 2.8321 -3.2639 270)
			(unlocked yes)
			(layer "B.Fab")
			(hide yes)
			(effects
				(font
					(size 1.016 1.016)
					(thickness 0.1524)
				)
				(justify mirror)
			)
		)
		(duplicate_pad_numbers_are_jumpers no)
		(fp_rect
			(start 0.2794 0.6477)
			(end -0.2794 -0.6477)
			(stroke
				(width 0)
				(type default)
			)
			(fill no)
			(layer "B.CrtYd")
		)
		(fp_rect
			(start 0.2794 0.6477)
			(end -0.2794 -0.6477)
			(stroke
				(width 0)
				(type default)
			)
			(fill no)
			(layer "B.Fab")
		)
		(pad "1" smd custom
			(at 0 -0.2794 90)
			(size 0.0762 0.0762)
			(layers "B.Cu" "B.Mask" "B.Paste")
			(net "DUT_AVD_TX")
			(options
				(clearance outline)
				(anchor circle)
			)
			(primitives
				(gr_poly
					(pts
						(arc
							(start 0.1524 0.127)
							(mid 0.137521 0.162921)
							(end 0.1016 0.1778)
						)
						(arc
							(start -0.1016 0.1778)
							(mid -0.137521 0.162921)
							(end -0.1524 0.127)
						)
						(arc
							(start -0.1524 -0.127)
							(mid -0.137521 -0.162921)
							(end -0.1016 -0.1778)
						)
						(arc
							(start 0.1016 -0.1778)
							(mid 0.137521 -0.162921)
							(end 0.1524 -0.127)
						)
					)
					(width 0)
					(fill yes)
				)
			)
		)
		(pad "2" smd custom
			(at 0 0.2794 90)
			(size 0.0762 0.0762)
			(layers "B.Cu" "B.Mask" "B.Paste")
			(net "GND")
			(options
				(clearance outline)
				(anchor circle)
			)
			(primitives
				(gr_poly
					(pts
						(arc
							(start 0.1524 0.127)
							(mid 0.137521 0.162921)
							(end 0.1016 0.1778)
						)
						(arc
							(start -0.1016 0.1778)
							(mid -0.137521 0.162921)
							(end -0.1524 0.127)
						)
						(arc
							(start -0.1524 -0.127)
							(mid -0.137521 -0.162921)
							(end -0.1016 -0.1778)
						)
						(arc
							(start 0.1016 -0.1778)
							(mid 0.137521 -0.162921)
							(end 0.1524 -0.127)
						)
					)
					(width 0)
					(fill yes)
				)
			)
		)
	)
	(footprint ""
		(layer "B.Cu")
		(at 66.938652 -121.3104 -90)
		(property "Reference" "R261"
			(at 0 0 90)
			(layer "B.SilkS")
			(hide yes)
			(effects
				(font
					(size 1.27 1.27)
				)
				(justify mirror)
			)
		)
		(property "Value" "0R2J-2-GP"
			(at -0.064008 -3.993896 270)
			(unlocked yes)
			(layer "B.Fab")
			(hide yes)
			(effects
				(font
					(size 1.016 1.016)
					(thickness 0.1524)
				)
				(justify mirror)
			)
		)
		(property "Device Type" "R402H16"
			(at -0.064008 -5.517896 270)
			(unlocked yes)
			(layer "B.Fab")
			(hide yes)
			(effects
				(font
					(size 1.016 1.016)
					(thickness 0.1524)
				)
				(justify mirror)
			)
		)
		(duplicate_pad_numbers_are_jumpers no)
		(fp_line
			(start -0.508 -0.9398)
			(end 0.508 -0.9398)
			(stroke
				(width 0.1524)
				(type default)
			)
			(layer "B.SilkS")
		)
		(fp_line
			(start 0.508 -0.9398)
			(end 0.508 0.9398)
			(stroke
				(width 0.1524)
				(type default)
			)
			(layer "B.SilkS")
		)
		(fp_rect
			(start 0.508 0.9398)
			(end -0.508 -0.9398)
			(stroke
				(width 0)
				(type default)
			)
			(fill no)
			(layer "B.CrtYd")
		)
		(fp_rect
			(start 0.508 0.9398)
			(end -0.508 -0.9398)
			(stroke
				(width 0)
				(type default)
			)
			(fill no)
			(layer "B.Fab")
		)
		(pad "1" smd custom
			(at 0 -0.4445 90)
			(size 0.1397 0.1397)
			(layers "B.Cu" "B.Mask" "B.Paste")
			(net "LAN_SMB_CLK")
			(options
				(clearance outline)
				(anchor circle)
			)
			(primitives
				(gr_poly
					(pts
						(arc
							(start -0.1778 0.2794)
							(mid -0.249642 0.249642)
							(end -0.2794 0.1778)
						)
						(arc
							(start -0.2794 -0.1778)
							(mid -0.249642 -0.249642)
							(end -0.1778 -0.2794)
						)
						(arc
							(start 0.1778 -0.2794)
							(mid 0.249642 -0.249642)
							(end 0.2794 -0.1778)
						)
						(arc
							(start 0.2794 0.1778)
							(mid 0.249642 0.249642)
							(end 0.1778 0.2794)
						)
					)
					(width 0)
					(fill yes)
				)
			)
		)
		(pad "2" smd custom
			(at 0 0.4445 90)
			(size 0.1397 0.1397)
			(layers "B.Cu" "B.Mask" "B.Paste")
			(net "BMC0_SMB4_CLK")
			(options
				(clearance outline)
				(anchor circle)
			)
			(primitives
				(gr_poly
					(pts
						(arc
							(start -0.1778 0.2794)
							(mid -0.249642 0.249642)
							(end -0.2794 0.1778)
						)
						(arc
							(start -0.2794 -0.1778)
							(mid -0.249642 -0.249642)
							(end -0.1778 -0.2794)
						)
						(arc
							(start 0.1778 -0.2794)
							(mid 0.249642 -0.249642)
							(end 0.2794 -0.1778)
						)
						(arc
							(start 0.2794 0.1778)
							(mid 0.249642 0.249642)
							(end 0.1778 0.2794)
						)
					)
					(width 0)
					(fill yes)
				)
			)
		)
	)
	(footprint ""
		(layer "B.Cu")
		(at 237.1598 -43.997372 90)
		(property "Reference" "C432"
			(at 0 0 90)
			(layer "B.SilkS")
			(hide yes)
			(effects
				(font
					(size 1.27 1.27)
				)
				(justify mirror)
			)
		)
		(property "Value" "SCD1U16V1KX-1-GP"
			(at 2.8321 -1.7399 90)
			(unlocked yes)
			(layer "B.Fab")
			(hide yes)
			(effects
				(font
					(size 1.016 1.016)
					(thickness 0.1524)
				)
				(justify mirror)
			)
		)
		(property "Device Type" "C0201H13"
			(at 2.8321 -3.2639 90)
			(unlocked yes)
			(layer "B.Fab")
			(hide yes)
			(effects
				(font
					(size 1.016 1.016)
					(thickness 0.1524)
				)
				(justify mirror)
			)
		)
		(duplicate_pad_numbers_are_jumpers no)
		(fp_rect
			(start 0.2794 0.6477)
			(end -0.2794 -0.6477)
			(stroke
				(width 0)
				(type default)
			)
			(fill no)
			(layer "B.CrtYd")
		)
		(fp_rect
			(start 0.2794 0.6477)
			(end -0.2794 -0.6477)
			(stroke
				(width 0)
				(type default)
			)
			(fill no)
			(layer "B.Fab")
		)
		(pad "1" smd custom
			(at 0 -0.2794 270)
			(size 0.0762 0.0762)
			(layers "B.Cu" "B.Mask" "B.Paste")
			(net "DUT_VDD")
			(options
				(clearance outline)
				(anchor circle)
			)
			(primitives
				(gr_poly
					(pts
						(arc
							(start 0.1524 0.127)
							(mid 0.137521 0.162921)
							(end 0.1016 0.1778)
						)
						(arc
							(start -0.1016 0.1778)
							(mid -0.137521 0.162921)
							(end -0.1524 0.127)
						)
						(arc
							(start -0.1524 -0.127)
							(mid -0.137521 -0.162921)
							(end -0.1016 -0.1778)
						)
						(arc
							(start 0.1016 -0.1778)
							(mid 0.137521 -0.162921)
							(end 0.1524 -0.127)
						)
					)
					(width 0)
					(fill yes)
				)
			)
		)
		(pad "2" smd custom
			(at 0 0.2794 270)
			(size 0.0762 0.0762)
			(layers "B.Cu" "B.Mask" "B.Paste")
			(net "GND")
			(options
				(clearance outline)
				(anchor circle)
			)
			(primitives
				(gr_poly
					(pts
						(arc
							(start 0.1524 0.127)
							(mid 0.137521 0.162921)
							(end 0.1016 0.1778)
						)
						(arc
							(start -0.1016 0.1778)
							(mid -0.137521 0.162921)
							(end -0.1524 0.127)
						)
						(arc
							(start -0.1524 -0.127)
							(mid -0.137521 -0.162921)
							(end -0.1016 -0.1778)
						)
						(arc
							(start 0.1016 -0.1778)
							(mid 0.137521 -0.162921)
							(end 0.1524 -0.127)
						)
					)
					(width 0)
					(fill yes)
				)
			)
		)
	)
	(footprint ""
		(layer "B.Cu")
		(at 61.341 -34.036 180)
		(property "Reference" "PR31"
			(at 0 0 0)
			(layer "B.SilkS")
			(hide yes)
			(effects
				(font
					(size 1.27 1.27)
				)
				(justify mirror)
			)
		)
		(property "Value" "121KR2F-L-GP"
			(at -0.064008 -3.993896 180)
			(unlocked yes)
			(layer "B.Fab")
			(hide yes)
			(effects
				(font
					(size 1.016 1.016)
					(thickness 0.1524)
				)
				(justify mirror)
			)
		)
		(property "Device Type" "R402H16"
			(at -0.064008 -5.517896 180)
			(unlocked yes)
			(layer "B.Fab")
			(hide yes)
			(effects
				(font
					(size 1.016 1.016)
					(thickness 0.1524)
				)
				(justify mirror)
			)
		)
		(duplicate_pad_numbers_are_jumpers no)
		(fp_line
			(start 0.508 -0.9398)
			(end 0.508 0.9398)
			(stroke
				(width 0.1524)
				(type default)
			)
			(layer "B.SilkS")
		)
		(fp_line
			(start -0.508 -0.9398)
			(end 0.508 -0.9398)
			(stroke
				(width 0.1524)
				(type default)
			)
			(layer "B.SilkS")
		)
		(fp_rect
			(start 0.508 0.9398)
			(end -0.508 -0.9398)
			(stroke
				(width 0)
				(type default)
			)
			(fill no)
			(layer "B.CrtYd")
		)
		(fp_rect
			(start 0.508 0.9398)
			(end -0.508 -0.9398)
			(stroke
				(width 0)
				(type default)
			)
			(fill no)
			(layer "B.Fab")
		)
		(pad "1" smd custom
			(at 0 -0.4445)
			(size 0.1397 0.1397)
			(layers "B.Cu" "B.Mask" "B.Paste")
			(net "AGND_P3V3_STBY")
			(options
				(clearance outline)
				(anchor circle)
			)
			(primitives
				(gr_poly
					(pts
						(arc
							(start -0.1778 0.2794)
							(mid -0.249642 0.249642)
							(end -0.2794 0.1778)
						)
						(arc
							(start -0.2794 -0.1778)
							(mid -0.249642 -0.249642)
							(end -0.1778 -0.2794)
						)
						(arc
							(start 0.1778 -0.2794)
							(mid 0.249642 -0.249642)
							(end 0.2794 -0.1778)
						)
						(arc
							(start 0.2794 0.1778)
							(mid 0.249642 0.249642)
							(end 0.1778 0.2794)
						)
					)
					(width 0)
					(fill yes)
				)
			)
		)
		(pad "2" smd custom
			(at 0 0.4445)
			(size 0.1397 0.1397)
			(layers "B.Cu" "B.Mask" "B.Paste")
			(net "P3V3_STBY_TRIP")
			(options
				(clearance outline)
				(anchor circle)
			)
			(primitives
				(gr_poly
					(pts
						(arc
							(start -0.1778 0.2794)
							(mid -0.249642 0.249642)
							(end -0.2794 0.1778)
						)
						(arc
							(start -0.2794 -0.1778)
							(mid -0.249642 -0.249642)
							(end -0.1778 -0.2794)
						)
						(arc
							(start 0.1778 -0.2794)
							(mid 0.249642 -0.249642)
							(end 0.2794 -0.1778)
						)
						(arc
							(start 0.2794 0.1778)
							(mid 0.249642 0.249642)
							(end 0.1778 0.2794)
						)
					)
					(width 0)
					(fill yes)
				)
			)
		)
	)
)
